(kicad_pcb
	(version 20260206)
	(generator "pcbnew")
	(generator_version "10.0")
	(general
		(thickness 1.6)
		(legacy_teardrops no)
	)
	(paper "A4")
	(title_block
		(title "03242023_DA0F0TMBIJ0_F0T_Motherboard_J_brd_V01_OCP.brd")
		(comment 1 "Grand Teton / footprints 4919-4924 of 6105")
	)
	(layers
		(0 "F.Cu" signal "TOP")
		(4 "In1.Cu" signal "GND")
		(6 "In2.Cu" signal "IN1")
		(8 "In3.Cu" signal "GND1")
		(10 "In4.Cu" signal "IN2")
		(12 "In5.Cu" signal "GND2")
		(14 "In6.Cu" signal "IN3")
		(16 "In7.Cu" signal "GND3")
		(18 "In8.Cu" signal "VCC")
		(20 "In9.Cu" signal "VCC1")
		(22 "In10.Cu" signal "GND4")
		(24 "In11.Cu" signal "IN4")
		(26 "In12.Cu" signal "GND5")
		(28 "In13.Cu" signal "IN5")
		(30 "In14.Cu" signal "GND6")
		(32 "In15.Cu" signal "IN6")
		(34 "In16.Cu" signal "GND7")
		(2 "B.Cu" signal "BOTTOM")
		(9 "F.Adhes" user "F.Adhesive")
		(11 "B.Adhes" user "B.Adhesive")
		(13 "F.Paste" user "Package Geometry/Pastemask Top")
		(15 "B.Paste" user "Package Geometry/Pastemask Bottom")
		(5 "F.SilkS" user "Ref Des/Silkscreen Top")
		(7 "B.SilkS" user "Ref Des/Silkscreen Bottom")
		(1 "F.Mask" user "Board Geometry/Soldermask Top")
		(3 "B.Mask" user "Board Geometry/Soldermask Bottom")
		(17 "Dwgs.User" user "User.Drawings")
		(19 "Cmts.User" user "User.Comments")
		(21 "Eco1.User" user "User.Eco1")
		(23 "Eco2.User" user "User.Eco2")
		(25 "Edge.Cuts" user "Board Geometry/Outline")
		(27 "Margin" user)
		(31 "F.CrtYd" user "Package Geometry/Place Bound Top")
		(29 "B.CrtYd" user "Package Geometry/Place Bound Bottom")
		(35 "F.Fab" user "Ref Des/Assembly Top")
		(33 "B.Fab" user "Ref Des/Assembly Bottom")
	)
	(footprint ""
		(layer "B.Cu")
		(at 54.50332 -344.727276 -90)
		(property "Reference" "PC408_P1_2"
			(at 0 0 90)
			(layer "B.SilkS")
			(hide yes)
			(effects
				(font
					(size 1.27 1.27)
				)
				(justify mirror)
			)
		)
		(property "Value" ""
			(at 0 0 90)
			(layer "B.Fab")
			(effects
				(font
					(size 1.27 1.27)
				)
				(justify mirror)
			)
		)
		(duplicate_pad_numbers_are_jumpers no)
		(fp_line
			(start -0.7874 0.4064)
			(end 0.7874 0.4064)
			(stroke
				(width 0.1524)
				(type default)
			)
			(layer "B.SilkS")
		)
		(fp_line
			(start 0.7874 0.4064)
			(end 0.7874 -0.4064)
			(stroke
				(width 0.1524)
				(type default)
			)
			(layer "B.SilkS")
		)
		(fp_line
			(start -0.7874 -0.4064)
			(end -0.7874 0.4064)
			(stroke
				(width 0.1524)
				(type default)
			)
			(layer "B.SilkS")
		)
		(fp_line
			(start 0.7874 -0.4064)
			(end -0.7874 -0.4064)
			(stroke
				(width 0.1524)
				(type default)
			)
			(layer "B.SilkS")
		)
		(fp_line
			(start -0.67945 0.3048)
			(end -0.120396 0.3048)
			(stroke
				(width 0.1)
				(type default)
			)
			(layer "B.Fab")
		)
		(fp_line
			(start -0.120396 0.3048)
			(end -0.120396 0.2794)
			(stroke
				(width 0.1)
				(type default)
			)
			(layer "B.Fab")
		)
		(fp_line
			(start 0.12065 0.3048)
			(end 0.67945 0.3048)
			(stroke
				(width 0.1)
				(type default)
			)
			(layer "B.Fab")
		)
		(fp_line
			(start 0.67945 0.3048)
			(end 0.67945 -0.305054)
			(stroke
				(width 0.1)
				(type default)
			)
			(layer "B.Fab")
		)
		(fp_line
			(start -0.120396 0.2794)
			(end 0.12065 0.2794)
			(stroke
				(width 0.1)
				(type default)
			)
			(layer "B.Fab")
		)
		(fp_line
			(start 0.12065 0.2794)
			(end 0.12065 0.3048)
			(stroke
				(width 0.1)
				(type default)
			)
			(layer "B.Fab")
		)
		(fp_line
			(start -0.12065 -0.2794)
			(end -0.12065 -0.3048)
			(stroke
				(width 0.1)
				(type default)
			)
			(layer "B.Fab")
		)
		(fp_line
			(start 0.12065 -0.2794)
			(end -0.12065 -0.2794)
			(stroke
				(width 0.1)
				(type default)
			)
			(layer "B.Fab")
		)
		(fp_line
			(start -0.67945 -0.3048)
			(end -0.67945 0.3048)
			(stroke
				(width 0.1)
				(type default)
			)
			(layer "B.Fab")
		)
		(fp_line
			(start -0.12065 -0.3048)
			(end -0.67945 -0.3048)
			(stroke
				(width 0.1)
				(type default)
			)
			(layer "B.Fab")
		)
		(fp_line
			(start 0.12065 -0.305054)
			(end 0.12065 -0.2794)
			(stroke
				(width 0.1)
				(type default)
			)
			(layer "B.Fab")
		)
		(fp_line
			(start 0.67945 -0.305054)
			(end 0.12065 -0.305054)
			(stroke
				(width 0.1)
				(type default)
			)
			(layer "B.Fab")
		)
		(pad "1" smd circle
			(at 0.40005 0 90)
			(size 0 0)
			(layers "B.Cu" "B.Mask" "B.Paste")
			(net "PVCCFA_EHV_FIVRA_CPU1")
		)
		(pad "2" smd circle
			(at -0.40005 0 90)
			(size 0 0)
			(layers "B.Cu" "B.Mask" "B.Paste")
			(net "GND")
		)
	)
	(footprint ""
		(layer "B.Cu")
		(at 288.464498 -403.031452 90)
		(property "Reference" "PR2514"
			(at 0 0 90)
			(layer "B.SilkS")
			(hide yes)
			(effects
				(font
					(size 1.27 1.27)
				)
				(justify mirror)
			)
		)
		(property "Value" ""
			(at 0 0 90)
			(layer "B.Fab")
			(effects
				(font
					(size 1.27 1.27)
				)
				(justify mirror)
			)
		)
		(duplicate_pad_numbers_are_jumpers no)
		(fp_line
			(start 0.7874 -0.4064)
			(end -0.7874 -0.4064)
			(stroke
				(width 0.1524)
				(type default)
			)
			(layer "B.SilkS")
		)
		(fp_line
			(start -0.7874 -0.4064)
			(end -0.7874 0.4064)
			(stroke
				(width 0.1524)
				(type default)
			)
			(layer "B.SilkS")
		)
		(fp_line
			(start 0.7874 0.4064)
			(end 0.7874 -0.4064)
			(stroke
				(width 0.1524)
				(type default)
			)
			(layer "B.SilkS")
		)
		(fp_line
			(start -0.7874 0.4064)
			(end 0.7874 0.4064)
			(stroke
				(width 0.1524)
				(type default)
			)
			(layer "B.SilkS")
		)
		(fp_line
			(start 0.67945 -0.305054)
			(end 0.12065 -0.305054)
			(stroke
				(width 0.1)
				(type default)
			)
			(layer "B.Fab")
		)
		(fp_line
			(start 0.12065 -0.305054)
			(end 0.12065 -0.2794)
			(stroke
				(width 0.1)
				(type default)
			)
			(layer "B.Fab")
		)
		(fp_line
			(start -0.12065 -0.3048)
			(end -0.67945 -0.3048)
			(stroke
				(width 0.1)
				(type default)
			)
			(layer "B.Fab")
		)
		(fp_line
			(start -0.67945 -0.3048)
			(end -0.67945 0.3048)
			(stroke
				(width 0.1)
				(type default)
			)
			(layer "B.Fab")
		)
		(fp_line
			(start 0.12065 -0.2794)
			(end -0.12065 -0.2794)
			(stroke
				(width 0.1)
				(type default)
			)
			(layer "B.Fab")
		)
		(fp_line
			(start -0.12065 -0.2794)
			(end -0.12065 -0.3048)
			(stroke
				(width 0.1)
				(type default)
			)
			(layer "B.Fab")
		)
		(fp_line
			(start 0.12065 0.2794)
			(end 0.12065 0.3048)
			(stroke
				(width 0.1)
				(type default)
			)
			(layer "B.Fab")
		)
		(fp_line
			(start -0.120396 0.2794)
			(end 0.12065 0.2794)
			(stroke
				(width 0.1)
				(type default)
			)
			(layer "B.Fab")
		)
		(fp_line
			(start 0.67945 0.3048)
			(end 0.67945 -0.305054)
			(stroke
				(width 0.1)
				(type default)
			)
			(layer "B.Fab")
		)
		(fp_line
			(start 0.12065 0.3048)
			(end 0.67945 0.3048)
			(stroke
				(width 0.1)
				(type default)
			)
			(layer "B.Fab")
		)
		(fp_line
			(start -0.120396 0.3048)
			(end -0.120396 0.2794)
			(stroke
				(width 0.1)
				(type default)
			)
			(layer "B.Fab")
		)
		(fp_line
			(start -0.67945 0.3048)
			(end -0.120396 0.3048)
			(stroke
				(width 0.1)
				(type default)
			)
			(layer "B.Fab")
		)
		(pad "1" smd circle
			(at 0.40005 0 270)
			(size 0 0)
			(layers "B.Cu" "B.Mask" "B.Paste")
			(net "P12V_HSC_ADC_P")
		)
		(pad "2" smd circle
			(at -0.40005 0 270)
			(size 0 0)
			(layers "B.Cu" "B.Mask" "B.Paste")
			(net "P12V_HSC_SENSE1_P")
		)
	)
	(footprint ""
		(layer "B.Cu")
		(at 433.328318 -177.15611 90)
		(property "Reference" "C1307"
			(at 0 0 90)
			(layer "B.SilkS")
			(hide yes)
			(effects
				(font
					(size 1.27 1.27)
				)
				(justify mirror)
			)
		)
		(property "Value" ""
			(at 0 0 90)
			(layer "B.Fab")
			(effects
				(font
					(size 1.27 1.27)
				)
				(justify mirror)
			)
		)
		(duplicate_pad_numbers_are_jumpers no)
		(fp_line
			(start 0.7874 -0.4064)
			(end -0.7874 -0.4064)
			(stroke
				(width 0.1524)
				(type default)
			)
			(layer "B.SilkS")
		)
		(fp_line
			(start -0.7874 -0.4064)
			(end -0.7874 0.4064)
			(stroke
				(width 0.1524)
				(type default)
			)
			(layer "B.SilkS")
		)
		(fp_line
			(start 0.7874 0.4064)
			(end 0.7874 -0.4064)
			(stroke
				(width 0.1524)
				(type default)
			)
			(layer "B.SilkS")
		)
		(fp_line
			(start -0.7874 0.4064)
			(end 0.7874 0.4064)
			(stroke
				(width 0.1524)
				(type default)
			)
			(layer "B.SilkS")
		)
		(fp_line
			(start 0.67945 -0.305054)
			(end 0.12065 -0.305054)
			(stroke
				(width 0.1)
				(type default)
			)
			(layer "B.Fab")
		)
		(fp_line
			(start 0.12065 -0.305054)
			(end 0.12065 -0.2794)
			(stroke
				(width 0.1)
				(type default)
			)
			(layer "B.Fab")
		)
		(fp_line
			(start -0.12065 -0.3048)
			(end -0.67945 -0.3048)
			(stroke
				(width 0.1)
				(type default)
			)
			(layer "B.Fab")
		)
		(fp_line
			(start -0.67945 -0.3048)
			(end -0.67945 0.3048)
			(stroke
				(width 0.1)
				(type default)
			)
			(layer "B.Fab")
		)
		(fp_line
			(start 0.12065 -0.2794)
			(end -0.12065 -0.2794)
			(stroke
				(width 0.1)
				(type default)
			)
			(layer "B.Fab")
		)
		(fp_line
			(start -0.12065 -0.2794)
			(end -0.12065 -0.3048)
			(stroke
				(width 0.1)
				(type default)
			)
			(layer "B.Fab")
		)
		(fp_line
			(start 0.12065 0.2794)
			(end 0.12065 0.3048)
			(stroke
				(width 0.1)
				(type default)
			)
			(layer "B.Fab")
		)
		(fp_line
			(start -0.120396 0.2794)
			(end 0.12065 0.2794)
			(stroke
				(width 0.1)
				(type default)
			)
			(layer "B.Fab")
		)
		(fp_line
			(start 0.67945 0.3048)
			(end 0.67945 -0.305054)
			(stroke
				(width 0.1)
				(type default)
			)
			(layer "B.Fab")
		)
		(fp_line
			(start 0.12065 0.3048)
			(end 0.67945 0.3048)
			(stroke
				(width 0.1)
				(type default)
			)
			(layer "B.Fab")
		)
		(fp_line
			(start -0.120396 0.3048)
			(end -0.120396 0.2794)
			(stroke
				(width 0.1)
				(type default)
			)
			(layer "B.Fab")
		)
		(fp_line
			(start -0.67945 0.3048)
			(end -0.120396 0.3048)
			(stroke
				(width 0.1)
				(type default)
			)
			(layer "B.Fab")
		)
		(pad "1" smd circle
			(at 0.40005 0 270)
			(size 0 0)
			(layers "B.Cu" "B.Mask" "B.Paste")
			(net "FM_PVNN_MAIN_CPU0_EN")
		)
		(pad "2" smd circle
			(at -0.40005 0 270)
			(size 0 0)
			(layers "B.Cu" "B.Mask" "B.Paste")
			(net "GND")
		)
	)
	(footprint ""
		(layer "B.Cu")
		(at 106.27995 -333.639922 90)
		(property "Reference" "PC566_P1_2"
			(at 0 0 90)
			(layer "B.SilkS")
			(hide yes)
			(effects
				(font
					(size 1.27 1.27)
				)
				(justify mirror)
			)
		)
		(property "Value" ""
			(at 0 0 90)
			(layer "B.Fab")
			(effects
				(font
					(size 1.27 1.27)
				)
				(justify mirror)
			)
		)
		(duplicate_pad_numbers_are_jumpers no)
		(fp_line
			(start 1.524 -0.762)
			(end -1.524 -0.762)
			(stroke
				(width 0.1524)
				(type default)
			)
			(layer "B.SilkS")
		)
		(fp_line
			(start -1.524 -0.762)
			(end -1.524 0.762)
			(stroke
				(width 0.1524)
				(type default)
			)
			(layer "B.SilkS")
		)
		(fp_line
			(start 1.524 0.762)
			(end 1.524 -0.762)
			(stroke
				(width 0.1524)
				(type default)
			)
			(layer "B.SilkS")
		)
		(fp_line
			(start -1.524 0.762)
			(end 1.524 0.762)
			(stroke
				(width 0.1524)
				(type default)
			)
			(layer "B.SilkS")
		)
		(fp_line
			(start 1.1049 -0.724916)
			(end 1.1049 0.724916)
			(stroke
				(width 0.1)
				(type default)
			)
			(layer "B.Fab")
		)
		(fp_line
			(start -1.1049 -0.724916)
			(end 1.1049 -0.724916)
			(stroke
				(width 0.1)
				(type default)
			)
			(layer "B.Fab")
		)
		(fp_line
			(start 1.1049 0.724916)
			(end -1.1049 0.724916)
			(stroke
				(width 0.1)
				(type default)
			)
			(layer "B.Fab")
		)
		(fp_line
			(start -1.1049 0.724916)
			(end -1.1049 -0.724916)
			(stroke
				(width 0.1)
				(type default)
			)
			(layer "B.Fab")
		)
		(pad "1" smd rect
			(at 0.889 0 90)
			(size 1.016 1.27)
			(layers "B.Cu" "B.Mask" "B.Paste")
			(net "SW_P12V_PVCCIN_CPU1_FLT")
		)
		(pad "2" smd rect
			(at -0.889 0 90)
			(size 1.016 1.27)
			(layers "B.Cu" "B.Mask" "B.Paste")
			(net "GND")
		)
	)
	(footprint ""
		(layer "B.Cu")
		(at 205.570582 -318.392048)
		(property "Reference" "R72"
			(at 0 0 0)
			(layer "B.SilkS")
			(hide yes)
			(effects
				(font
					(size 1.27 1.27)
				)
				(justify mirror)
			)
		)
		(property "Value" ""
			(at 0 0 0)
			(layer "B.Fab")
			(effects
				(font
					(size 1.27 1.27)
				)
				(justify mirror)
			)
		)
		(duplicate_pad_numbers_are_jumpers no)
		(fp_line
			(start -0.7874 -0.4064)
			(end -0.7874 0.4064)
			(stroke
				(width 0.1524)
				(type default)
			)
			(layer "B.SilkS")
		)
		(fp_line
			(start -0.7874 0.4064)
			(end 0.7874 0.4064)
			(stroke
				(width 0.1524)
				(type default)
			)
			(layer "B.SilkS")
		)
		(fp_line
			(start 0.7874 -0.4064)
			(end -0.7874 -0.4064)
			(stroke
				(width 0.1524)
				(type default)
			)
			(layer "B.SilkS")
		)
		(fp_line
			(start 0.7874 0.4064)
			(end 0.7874 -0.4064)
			(stroke
				(width 0.1524)
				(type default)
			)
			(layer "B.SilkS")
		)
		(fp_line
			(start -0.67945 -0.3048)
			(end -0.67945 0.3048)
			(stroke
				(width 0.1)
				(type default)
			)
			(layer "B.Fab")
		)
		(fp_line
			(start -0.67945 0.3048)
			(end -0.120396 0.3048)
			(stroke
				(width 0.1)
				(type default)
			)
			(layer "B.Fab")
		)
		(fp_line
			(start -0.12065 -0.3048)
			(end -0.67945 -0.3048)
			(stroke
				(width 0.1)
				(type default)
			)
			(layer "B.Fab")
		)
		(fp_line
			(start -0.12065 -0.2794)
			(end -0.12065 -0.3048)
			(stroke
				(width 0.1)
				(type default)
			)
			(layer "B.Fab")
		)
		(fp_line
			(start -0.120396 0.2794)
			(end 0.12065 0.2794)
			(stroke
				(width 0.1)
				(type default)
			)
			(layer "B.Fab")
		)
		(fp_line
			(start -0.120396 0.3048)
			(end -0.120396 0.2794)
			(stroke
				(width 0.1)
				(type default)
			)
			(layer "B.Fab")
		)
		(fp_line
			(start 0.12065 -0.305054)
			(end 0.12065 -0.2794)
			(stroke
				(width 0.1)
				(type default)
			)
			(layer "B.Fab")
		)
		(fp_line
			(start 0.12065 -0.2794)
			(end -0.12065 -0.2794)
			(stroke
				(width 0.1)
				(type default)
			)
			(layer "B.Fab")
		)
		(fp_line
			(start 0.12065 0.2794)
			(end 0.12065 0.3048)
			(stroke
				(width 0.1)
				(type default)
			)
			(layer "B.Fab")
		)
		(fp_line
			(start 0.12065 0.3048)
			(end 0.67945 0.3048)
			(stroke
				(width 0.1)
				(type default)
			)
			(layer "B.Fab")
		)
		(fp_line
			(start 0.67945 -0.305054)
			(end 0.12065 -0.305054)
			(stroke
				(width 0.1)
				(type default)
			)
			(layer "B.Fab")
		)
		(fp_line
			(start 0.67945 0.3048)
			(end 0.67945 -0.305054)
			(stroke
				(width 0.1)
				(type default)
			)
			(layer "B.Fab")
		)
		(pad "1" smd circle
			(at 0.40005 0 180)
			(size 0 0)
			(layers "B.Cu" "B.Mask" "B.Paste")
			(net "PD_CHH_CPU1_DIMM2_SAA")
		)
		(pad "2" smd circle
			(at -0.40005 0 180)
			(size 0 0)
			(layers "B.Cu" "B.Mask" "B.Paste")
			(net "GND")
		)
	)
	(footprint ""
		(layer "B.Cu")
		(at 298.566332 -152.038558 180)
		(property "Reference" "U15"
			(at -1.392936 -4.58851 0)
			(unlocked yes)
			(layer "B.SilkS")
			(effects
				(font
					(size 0.7874 0.5842)
					(thickness 0.1524)
				)
				(justify left mirror)
			)
		)
		(property "Value" ""
			(at 0 0 0)
			(layer "B.Fab")
			(effects
				(font
					(size 1.27 1.27)
				)
				(justify mirror)
			)
		)
		(duplicate_pad_numbers_are_jumpers no)
		(fp_line
			(start 1.7272 2.489962)
			(end 1.7272 -2.489962)
			(stroke
				(width 0.1524)
				(type default)
			)
			(layer "B.SilkS")
		)
		(fp_line
			(start 1.7272 -2.489962)
			(end 0.779018 -2.489962)
			(stroke
				(width 0.1524)
				(type default)
			)
			(layer "B.SilkS")
		)
		(fp_line
			(start 0.779018 -2.489962)
			(end 0 -1.710944)
			(stroke
				(width 0.1524)
				(type default)
			)
			(layer "B.SilkS")
		)
		(fp_line
			(start 0 -1.710944)
			(end -0.779018 -2.489962)
			(stroke
				(width 0.1524)
				(type default)
			)
			(layer "B.SilkS")
		)
		(fp_line
			(start -0.779018 -2.489962)
			(end -1.7272 -2.489962)
			(stroke
				(width 0.1524)
				(type default)
			)
			(layer "B.SilkS")
		)
		(fp_line
			(start -1.7272 2.489962)
			(end 1.7272 2.489962)
			(stroke
				(width 0.1524)
				(type default)
			)
			(layer "B.SilkS")
		)
		(fp_line
			(start -1.7272 -2.489962)
			(end -1.7272 2.489962)
			(stroke
				(width 0.1524)
				(type default)
			)
			(layer "B.SilkS")
		)
		(fp_poly
			(pts
				(xy 3.307842 -3.782314) (xy 2.799842 -2.766314) (xy 2.291842 -3.782314)
			)
			(stroke
				(width 0)
				(type default)
			)
			(fill yes)
			(layer "B.SilkS")
		)
		(fp_line
			(start 1.994916 2.489962)
			(end 1.994916 -2.489962)
			(stroke
				(width 0.1)
				(type default)
			)
			(layer "B.Fab")
		)
		(fp_line
			(start 1.994916 -2.489962)
			(end -1.994916 -2.489962)
			(stroke
				(width 0.1)
				(type default)
			)
			(layer "B.Fab")
		)
		(fp_line
			(start -1.994916 2.489962)
			(end 1.994916 2.489962)
			(stroke
				(width 0.1)
				(type default)
			)
			(layer "B.Fab")
		)
		(fp_line
			(start -1.994916 -2.489962)
			(end -1.994916 2.489962)
			(stroke
				(width 0.1)
				(type default)
			)
			(layer "B.Fab")
		)
		(fp_poly
			(pts
				(xy 4.837176 -2.7305) (xy 4.837176 -1.7145) (xy 3.821176 -2.2225)
			)
			(stroke
				(width 0)
				(type default)
			)
			(fill yes)
			(layer "B.Fab")
		)
		(pad "1" smd rect
			(at 2.6924 -2.2225 90)
			(size 0.4318 1.6764)
			(layers "B.Cu" "B.Mask" "B.Paste")
			(net "FM_SPD_REMOTE_EN")
		)
		(pad "2" smd rect
			(at 2.6924 -1.5875 90)
			(size 0.4318 1.6764)
			(layers "B.Cu" "B.Mask" "B.Paste")
			(net "I3C_SPD_DDRABCD_CPU0_R_SCL")
		)
		(pad "3" smd rect
			(at 2.6924 -0.9525 90)
			(size 0.4318 1.6764)
			(layers "B.Cu" "B.Mask" "B.Paste")
			(net "I3C_SPD_DDRABCD_CPU0_BMC_SCL")
		)
		(pad "4" smd rect
			(at 2.6924 -0.3175 90)
			(size 0.4318 1.6764)
			(layers "B.Cu" "B.Mask" "B.Paste")
			(net "I3C_SPD_DDRABCD_CPU0_LVC1_R_SCL")
		)
		(pad "5" smd rect
			(at 2.6924 0.3175 90)
			(size 0.4318 1.6764)
			(layers "B.Cu" "B.Mask" "B.Paste")
			(net "I3C_SPD_DDRABCD_CPU0_R_SDA")
		)
		(pad "6" smd rect
			(at 2.6924 0.9525 90)
			(size 0.4318 1.6764)
			(layers "B.Cu" "B.Mask" "B.Paste")
			(net "I3C_SPD_DDRABCD_CPU0_BMC_SDA")
		)
		(pad "7" smd rect
			(at 2.6924 1.5875 90)
			(size 0.4318 1.6764)
			(layers "B.Cu" "B.Mask" "B.Paste")
			(net "I3C_SPD_DDRABCD_CPU0_LVC1_R_SDA")
		)
		(pad "8" smd rect
			(at 2.6924 2.2225 90)
			(size 0.4318 1.6764)
			(layers "B.Cu" "B.Mask" "B.Paste")
			(net "GND")
		)
		(pad "9" smd rect
			(at -2.6924 2.2225 90)
			(size 0.4318 1.6764)
			(layers "B.Cu" "B.Mask" "B.Paste")
			(net "I3C_SPD_DDREFGH_CPU0_LVC1_R_SCL")
		)
		(pad "10" smd rect
			(at -2.6924 1.5875 90)
			(size 0.4318 1.6764)
			(layers "B.Cu" "B.Mask" "B.Paste")
			(net "I3C_SPD_DDREFGH_CPU0_BMC_SCL")
		)
		(pad "11" smd rect
			(at -2.6924 0.9525 90)
			(size 0.4318 1.6764)
			(layers "B.Cu" "B.Mask" "B.Paste")
			(net "I3C_SPD_DDREFGH_CPU0_R_SCL")
		)
		(pad "12" smd rect
			(at -2.6924 0.3175 90)
			(size 0.4318 1.6764)
			(layers "B.Cu" "B.Mask" "B.Paste")
			(net "I3C_SPD_DDREFGH_CPU0_LVC1_R_SDA")
		)
		(pad "13" smd rect
			(at -2.6924 -0.3175 90)
			(size 0.4318 1.6764)
			(layers "B.Cu" "B.Mask" "B.Paste")
			(net "I3C_SPD_DDREFGH_CPU0_BMC_SDA")
		)
		(pad "14" smd rect
			(at -2.6924 -0.9525 90)
			(size 0.4318 1.6764)
			(layers "B.Cu" "B.Mask" "B.Paste")
			(net "I3C_SPD_DDREFGH_CPU0_R_SDA")
		)
		(pad "15" smd rect
			(at -2.6924 -1.5875 90)
			(size 0.4318 1.6764)
			(layers "B.Cu" "B.Mask" "B.Paste")
			(net "PD_I3C_SPD_DDR_CPU0_OE_N")
		)
		(pad "16" smd rect
			(at -2.6924 -2.2225 90)
			(size 0.4318 1.6764)
			(layers "B.Cu" "B.Mask" "B.Paste")
			(net "P3V3_AUX")
		)
	)
)
